(kicad_pcb
	(version 20260206)
	(generator "pcbnew")
	(generator_version "10.0")
	(general
		(thickness 1.6)
		(legacy_teardrops no)
	)
	(paper "A4")
	(title_block
		(title "01162023_DA0F0TEBIF0_F0T_Expander_BD_F_brd_V02_OCP.brd")
		(comment 1 "Grand Teton / footprints 9258-9265 of 9728")
	)
	(layers
		(0 "F.Cu" signal "TOP")
		(4 "In1.Cu" signal "GND")
		(6 "In2.Cu" signal "VCC")
		(8 "In3.Cu" signal "VCC1")
		(10 "In4.Cu" signal "GND1")
		(12 "In5.Cu" signal "IN1")
		(14 "In6.Cu" signal "GND2")
		(16 "In7.Cu" signal "IN2")
		(18 "In8.Cu" signal "GND3")
		(20 "In9.Cu" signal "IN3")
		(22 "In10.Cu" signal "GND4")
		(24 "In11.Cu" signal "IN4")
		(26 "In12.Cu" signal "GND5")
		(28 "In13.Cu" signal "IN5")
		(30 "In14.Cu" signal "GND6")
		(32 "In15.Cu" signal "IN6")
		(34 "In16.Cu" signal "GND7")
		(2 "B.Cu" signal "BOTTOM")
		(9 "F.Adhes" user "F.Adhesive")
		(11 "B.Adhes" user "B.Adhesive")
		(13 "F.Paste" user "Package Geometry/Pastemask Top")
		(15 "B.Paste" user "Package Geometry/Pastemask Bottom")
		(5 "F.SilkS" user "Ref Des/Silkscreen Top")
		(7 "B.SilkS" user "Ref Des/Silkscreen Bottom")
		(1 "F.Mask" user "Board Geometry/Soldermask Top")
		(3 "B.Mask" user "Board Geometry/Soldermask Bottom")
		(17 "Dwgs.User" user "User.Drawings")
		(19 "Cmts.User" user "User.Comments")
		(21 "Eco1.User" user "User.Eco1")
		(23 "Eco2.User" user "User.Eco2")
		(25 "Edge.Cuts" user "Board Geometry/Outline")
		(27 "Margin" user)
		(31 "F.CrtYd" user "Package Geometry/Place Bound Top")
		(29 "B.CrtYd" user "Package Geometry/Place Bound Bottom")
		(35 "F.Fab" user "Ref Des/Assembly Top")
		(33 "B.Fab" user "Ref Des/Assembly Bottom")
	)
	(footprint ""
		(layer "B.Cu")
		(at 177.649886 -299.699934 -90)
		(property "Reference" "C1474"
			(at 0 0 90)
			(layer "B.SilkS")
			(hide yes)
			(effects
				(font
					(size 1.27 1.27)
				)
				(justify mirror)
			)
		)
		(property "Value" ""
			(at 0 0 90)
			(layer "B.Fab")
			(effects
				(font
					(size 1.27 1.27)
				)
				(justify mirror)
			)
		)
		(duplicate_pad_numbers_are_jumpers no)
		(fp_line
			(start -0.299974 0.150114)
			(end 0.299974 0.150114)
			(stroke
				(width 0.1)
				(type default)
			)
			(layer "B.Fab")
		)
		(fp_line
			(start 0.299974 0.150114)
			(end 0.299974 -0.150114)
			(stroke
				(width 0.1)
				(type default)
			)
			(layer "B.Fab")
		)
		(fp_line
			(start -0.299974 -0.150114)
			(end -0.299974 0.150114)
			(stroke
				(width 0.1)
				(type default)
			)
			(layer "B.Fab")
		)
		(fp_line
			(start 0.299974 -0.150114)
			(end -0.299974 -0.150114)
			(stroke
				(width 0.1)
				(type default)
			)
			(layer "B.Fab")
		)
		(pad "1" smd rect
			(at 0.2667 0 90)
			(size 0.3048 0.381)
			(layers "B.Cu" "B.Mask" "B.Paste")
			(net "P0V8_SERDES_VDDA_PEX1")
		)
		(pad "2" smd rect
			(at -0.2667 0 90)
			(size 0.3048 0.381)
			(layers "B.Cu" "B.Mask" "B.Paste")
			(net "GND")
		)
	)
	(footprint ""
		(layer "B.Cu")
		(at 55.374794 -293.99992 -90)
		(property "Reference" "C1147"
			(at 0 0 90)
			(layer "B.SilkS")
			(hide yes)
			(effects
				(font
					(size 1.27 1.27)
				)
				(justify mirror)
			)
		)
		(property "Value" ""
			(at 0 0 90)
			(layer "B.Fab")
			(effects
				(font
					(size 1.27 1.27)
				)
				(justify mirror)
			)
		)
		(duplicate_pad_numbers_are_jumpers no)
		(fp_line
			(start -0.299974 0.150114)
			(end 0.299974 0.150114)
			(stroke
				(width 0.1)
				(type default)
			)
			(layer "B.Fab")
		)
		(fp_line
			(start 0.299974 0.150114)
			(end 0.299974 -0.150114)
			(stroke
				(width 0.1)
				(type default)
			)
			(layer "B.Fab")
		)
		(fp_line
			(start -0.299974 -0.150114)
			(end -0.299974 0.150114)
			(stroke
				(width 0.1)
				(type default)
			)
			(layer "B.Fab")
		)
		(fp_line
			(start 0.299974 -0.150114)
			(end -0.299974 -0.150114)
			(stroke
				(width 0.1)
				(type default)
			)
			(layer "B.Fab")
		)
		(pad "1" smd rect
			(at 0.2667 0 90)
			(size 0.3048 0.381)
			(layers "B.Cu" "B.Mask" "B.Paste")
			(net "P0V8_PEX0")
		)
		(pad "2" smd rect
			(at -0.2667 0 90)
			(size 0.3048 0.381)
			(layers "B.Cu" "B.Mask" "B.Paste")
			(net "GND")
		)
	)
	(footprint ""
		(layer "B.Cu")
		(at 9.292844 -276.029928 180)
		(property "Reference" "C4218"
			(at 0 0 0)
			(layer "B.SilkS")
			(hide yes)
			(effects
				(font
					(size 1.27 1.27)
				)
				(justify mirror)
			)
		)
		(property "Value" ""
			(at 0 0 0)
			(layer "B.Fab")
			(effects
				(font
					(size 1.27 1.27)
				)
				(justify mirror)
			)
		)
		(duplicate_pad_numbers_are_jumpers no)
		(fp_line
			(start 1.2954 0.5842)
			(end 1.2954 -0.5842)
			(stroke
				(width 0.1524)
				(type default)
			)
			(layer "B.SilkS")
		)
		(fp_line
			(start 1.2954 -0.5842)
			(end -1.2954 -0.5842)
			(stroke
				(width 0.1524)
				(type default)
			)
			(layer "B.SilkS")
		)
		(fp_line
			(start -1.2954 0.5842)
			(end 1.2954 0.5842)
			(stroke
				(width 0.1524)
				(type default)
			)
			(layer "B.SilkS")
		)
		(fp_line
			(start -1.2954 -0.5842)
			(end -1.2954 0.5842)
			(stroke
				(width 0.1524)
				(type default)
			)
			(layer "B.SilkS")
		)
		(fp_line
			(start 1.1938 0.4064)
			(end 1.1938 -0.4064)
			(stroke
				(width 0.1)
				(type default)
			)
			(layer "B.Fab")
		)
		(fp_line
			(start 1.1938 -0.4064)
			(end 0.8636 -0.4064)
			(stroke
				(width 0.1)
				(type default)
			)
			(layer "B.Fab")
		)
		(fp_line
			(start 0.8636 0.4572)
			(end 0.8636 0.4064)
			(stroke
				(width 0.1)
				(type default)
			)
			(layer "B.Fab")
		)
		(fp_line
			(start 0.8636 0.4064)
			(end 1.1938 0.4064)
			(stroke
				(width 0.1)
				(type default)
			)
			(layer "B.Fab")
		)
		(fp_line
			(start 0.8636 -0.4064)
			(end 0.8636 -0.4572)
			(stroke
				(width 0.1)
				(type default)
			)
			(layer "B.Fab")
		)
		(fp_line
			(start 0.8636 -0.4572)
			(end -0.8636 -0.4572)
			(stroke
				(width 0.1)
				(type default)
			)
			(layer "B.Fab")
		)
		(fp_line
			(start -0.8636 0.4572)
			(end 0.8636 0.4572)
			(stroke
				(width 0.1)
				(type default)
			)
			(layer "B.Fab")
		)
		(fp_line
			(start -0.8636 0.4064)
			(end -0.8636 0.4572)
			(stroke
				(width 0.1)
				(type default)
			)
			(layer "B.Fab")
		)
		(fp_line
			(start -0.8636 -0.4064)
			(end -1.1938 -0.4064)
			(stroke
				(width 0.1)
				(type default)
			)
			(layer "B.Fab")
		)
		(fp_line
			(start -0.8636 -0.4572)
			(end -0.8636 -0.4064)
			(stroke
				(width 0.1)
				(type default)
			)
			(layer "B.Fab")
		)
		(fp_line
			(start -1.1938 0.4064)
			(end -0.8636 0.4064)
			(stroke
				(width 0.1)
				(type default)
			)
			(layer "B.Fab")
		)
		(fp_line
			(start -1.1938 -0.4064)
			(end -1.1938 0.4064)
			(stroke
				(width 0.1)
				(type default)
			)
			(layer "B.Fab")
		)
		(pad "1" smd rect
			(at 0.7366 0 90)
			(size 0.7112 0.8128)
			(layers "B.Cu" "B.Mask" "B.Paste")
			(net "P1V25_PEX0")
		)
		(pad "2" smd rect
			(at -0.7366 0 90)
			(size 0.7112 0.8128)
			(layers "B.Cu" "B.Mask" "B.Paste")
			(net "GND")
		)
	)
	(footprint ""
		(layer "B.Cu")
		(at 365.087408 -282.173426 90)
		(property "Reference" "R6769"
			(at 0 0 90)
			(layer "B.SilkS")
			(hide yes)
			(effects
				(font
					(size 1.27 1.27)
				)
				(justify mirror)
			)
		)
		(property "Value" ""
			(at 0 0 90)
			(layer "B.Fab")
			(effects
				(font
					(size 1.27 1.27)
				)
				(justify mirror)
			)
		)
		(duplicate_pad_numbers_are_jumpers no)
		(fp_line
			(start 0.7874 -0.4064)
			(end -0.7874 -0.4064)
			(stroke
				(width 0.1524)
				(type default)
			)
			(layer "B.SilkS")
		)
		(fp_line
			(start -0.7874 -0.4064)
			(end -0.7874 0.4064)
			(stroke
				(width 0.1524)
				(type default)
			)
			(layer "B.SilkS")
		)
		(fp_line
			(start 0.7874 0.4064)
			(end 0.7874 -0.4064)
			(stroke
				(width 0.1524)
				(type default)
			)
			(layer "B.SilkS")
		)
		(fp_line
			(start -0.7874 0.4064)
			(end 0.7874 0.4064)
			(stroke
				(width 0.1524)
				(type default)
			)
			(layer "B.SilkS")
		)
		(fp_line
			(start 0.67945 -0.305054)
			(end 0.12065 -0.305054)
			(stroke
				(width 0.1)
				(type default)
			)
			(layer "B.Fab")
		)
		(fp_line
			(start 0.12065 -0.305054)
			(end 0.12065 -0.2794)
			(stroke
				(width 0.1)
				(type default)
			)
			(layer "B.Fab")
		)
		(fp_line
			(start -0.12065 -0.3048)
			(end -0.67945 -0.3048)
			(stroke
				(width 0.1)
				(type default)
			)
			(layer "B.Fab")
		)
		(fp_line
			(start -0.67945 -0.3048)
			(end -0.67945 0.3048)
			(stroke
				(width 0.1)
				(type default)
			)
			(layer "B.Fab")
		)
		(fp_line
			(start 0.12065 -0.2794)
			(end -0.12065 -0.2794)
			(stroke
				(width 0.1)
				(type default)
			)
			(layer "B.Fab")
		)
		(fp_line
			(start -0.12065 -0.2794)
			(end -0.12065 -0.3048)
			(stroke
				(width 0.1)
				(type default)
			)
			(layer "B.Fab")
		)
		(fp_line
			(start 0.12065 0.2794)
			(end 0.12065 0.3048)
			(stroke
				(width 0.1)
				(type default)
			)
			(layer "B.Fab")
		)
		(fp_line
			(start -0.120396 0.2794)
			(end 0.12065 0.2794)
			(stroke
				(width 0.1)
				(type default)
			)
			(layer "B.Fab")
		)
		(fp_line
			(start 0.67945 0.3048)
			(end 0.67945 -0.305054)
			(stroke
				(width 0.1)
				(type default)
			)
			(layer "B.Fab")
		)
		(fp_line
			(start 0.12065 0.3048)
			(end 0.67945 0.3048)
			(stroke
				(width 0.1)
				(type default)
			)
			(layer "B.Fab")
		)
		(fp_line
			(start -0.120396 0.3048)
			(end -0.120396 0.2794)
			(stroke
				(width 0.1)
				(type default)
			)
			(layer "B.Fab")
		)
		(fp_line
			(start -0.67945 0.3048)
			(end -0.120396 0.3048)
			(stroke
				(width 0.1)
				(type default)
			)
			(layer "B.Fab")
		)
		(pad "1" smd circle
			(at 0.40005 0 270)
			(size 0 0)
			(layers "B.Cu" "B.Mask" "B.Paste")
			(net "P0V8_PEX3_VCC2")
		)
		(pad "2" smd circle
			(at -0.40005 0 270)
			(size 0 0)
			(layers "B.Cu" "B.Mask" "B.Paste")
			(net "P0V8_PEX2_EN4")
		)
	)
	(footprint ""
		(layer "B.Cu")
		(at 70.104 -98.552)
		(property "Reference" "R74"
			(at 0 0 0)
			(layer "B.SilkS")
			(hide yes)
			(effects
				(font
					(size 1.27 1.27)
				)
				(justify mirror)
			)
		)
		(property "Value" ""
			(at 0 0 0)
			(layer "B.Fab")
			(effects
				(font
					(size 1.27 1.27)
				)
				(justify mirror)
			)
		)
		(duplicate_pad_numbers_are_jumpers no)
		(fp_line
			(start -0.7874 -0.4064)
			(end -0.7874 0.4064)
			(stroke
				(width 0.1524)
				(type default)
			)
			(layer "B.SilkS")
		)
		(fp_line
			(start -0.7874 0.4064)
			(end 0.7874 0.4064)
			(stroke
				(width 0.1524)
				(type default)
			)
			(layer "B.SilkS")
		)
		(fp_line
			(start 0.7874 -0.4064)
			(end -0.7874 -0.4064)
			(stroke
				(width 0.1524)
				(type default)
			)
			(layer "B.SilkS")
		)
		(fp_line
			(start 0.7874 0.4064)
			(end 0.7874 -0.4064)
			(stroke
				(width 0.1524)
				(type default)
			)
			(layer "B.SilkS")
		)
		(fp_line
			(start -0.67945 -0.3048)
			(end -0.67945 0.3048)
			(stroke
				(width 0.1)
				(type default)
			)
			(layer "B.Fab")
		)
		(fp_line
			(start -0.67945 0.3048)
			(end -0.120396 0.3048)
			(stroke
				(width 0.1)
				(type default)
			)
			(layer "B.Fab")
		)
		(fp_line
			(start -0.12065 -0.3048)
			(end -0.67945 -0.3048)
			(stroke
				(width 0.1)
				(type default)
			)
			(layer "B.Fab")
		)
		(fp_line
			(start -0.12065 -0.2794)
			(end -0.12065 -0.3048)
			(stroke
				(width 0.1)
				(type default)
			)
			(layer "B.Fab")
		)
		(fp_line
			(start -0.120396 0.2794)
			(end 0.12065 0.2794)
			(stroke
				(width 0.1)
				(type default)
			)
			(layer "B.Fab")
		)
		(fp_line
			(start -0.120396 0.3048)
			(end -0.120396 0.2794)
			(stroke
				(width 0.1)
				(type default)
			)
			(layer "B.Fab")
		)
		(fp_line
			(start 0.12065 -0.305054)
			(end 0.12065 -0.2794)
			(stroke
				(width 0.1)
				(type default)
			)
			(layer "B.Fab")
		)
		(fp_line
			(start 0.12065 -0.2794)
			(end -0.12065 -0.2794)
			(stroke
				(width 0.1)
				(type default)
			)
			(layer "B.Fab")
		)
		(fp_line
			(start 0.12065 0.2794)
			(end 0.12065 0.3048)
			(stroke
				(width 0.1)
				(type default)
			)
			(layer "B.Fab")
		)
		(fp_line
			(start 0.12065 0.3048)
			(end 0.67945 0.3048)
			(stroke
				(width 0.1)
				(type default)
			)
			(layer "B.Fab")
		)
		(fp_line
			(start 0.67945 -0.305054)
			(end 0.12065 -0.305054)
			(stroke
				(width 0.1)
				(type default)
			)
			(layer "B.Fab")
		)
		(fp_line
			(start 0.67945 0.3048)
			(end 0.67945 -0.305054)
			(stroke
				(width 0.1)
				(type default)
			)
			(layer "B.Fab")
		)
		(pad "1" smd circle
			(at 0.40005 0 180)
			(size 0 0)
			(layers "B.Cu" "B.Mask" "B.Paste")
			(net "NIC1_MAIN_PWR_EN")
		)
		(pad "2" smd circle
			(at -0.40005 0 180)
			(size 0 0)
			(layers "B.Cu" "B.Mask" "B.Paste")
			(net "GND")
		)
	)
	(footprint ""
		(layer "B.Cu")
		(at 162.455098 -299.212)
		(property "Reference" "C3200"
			(at 0 0 0)
			(layer "B.SilkS")
			(hide yes)
			(effects
				(font
					(size 1.27 1.27)
				)
				(justify mirror)
			)
		)
		(property "Value" ""
			(at 0 0 0)
			(layer "B.Fab")
			(effects
				(font
					(size 1.27 1.27)
				)
				(justify mirror)
			)
		)
		(duplicate_pad_numbers_are_jumpers no)
		(fp_line
			(start -0.299974 -0.150114)
			(end -0.299974 0.150114)
			(stroke
				(width 0.1)
				(type default)
			)
			(layer "B.Fab")
		)
		(fp_line
			(start -0.299974 0.150114)
			(end 0.299974 0.150114)
			(stroke
				(width 0.1)
				(type default)
			)
			(layer "B.Fab")
		)
		(fp_line
			(start 0.299974 -0.150114)
			(end -0.299974 -0.150114)
			(stroke
				(width 0.1)
				(type default)
			)
			(layer "B.Fab")
		)
		(fp_line
			(start 0.299974 0.150114)
			(end 0.299974 -0.150114)
			(stroke
				(width 0.1)
				(type default)
			)
			(layer "B.Fab")
		)
		(pad "1" smd rect
			(at 0.2667 0 180)
			(size 0.3048 0.381)
			(layers "B.Cu" "B.Mask" "B.Paste")
			(net "PCEPLL1_VDDA18_PEX1")
		)
		(pad "2" smd rect
			(at -0.2667 0 180)
			(size 0.3048 0.381)
			(layers "B.Cu" "B.Mask" "B.Paste")
			(net "GND")
		)
	)
	(footprint ""
		(layer "B.Cu")
		(at 166.743888 -138.421618 180)
		(property "Reference" "R126"
			(at 0 0 0)
			(layer "B.SilkS")
			(hide yes)
			(effects
				(font
					(size 1.27 1.27)
				)
				(justify mirror)
			)
		)
		(property "Value" ""
			(at 0 0 0)
			(layer "B.Fab")
			(effects
				(font
					(size 1.27 1.27)
				)
				(justify mirror)
			)
		)
		(duplicate_pad_numbers_are_jumpers no)
		(fp_line
			(start 0.7874 0.4064)
			(end 0.7874 -0.4064)
			(stroke
				(width 0.1524)
				(type default)
			)
			(layer "B.SilkS")
		)
		(fp_line
			(start 0.7874 -0.4064)
			(end -0.7874 -0.4064)
			(stroke
				(width 0.1524)
				(type default)
			)
			(layer "B.SilkS")
		)
		(fp_line
			(start -0.7874 0.4064)
			(end 0.7874 0.4064)
			(stroke
				(width 0.1524)
				(type default)
			)
			(layer "B.SilkS")
		)
		(fp_line
			(start -0.7874 -0.4064)
			(end -0.7874 0.4064)
			(stroke
				(width 0.1524)
				(type default)
			)
			(layer "B.SilkS")
		)
		(fp_line
			(start 0.67945 0.3048)
			(end 0.67945 -0.305054)
			(stroke
				(width 0.1)
				(type default)
			)
			(layer "B.Fab")
		)
		(fp_line
			(start 0.67945 -0.305054)
			(end 0.12065 -0.305054)
			(stroke
				(width 0.1)
				(type default)
			)
			(layer "B.Fab")
		)
		(fp_line
			(start 0.12065 0.3048)
			(end 0.67945 0.3048)
			(stroke
				(width 0.1)
				(type default)
			)
			(layer "B.Fab")
		)
		(fp_line
			(start 0.12065 0.2794)
			(end 0.12065 0.3048)
			(stroke
				(width 0.1)
				(type default)
			)
			(layer "B.Fab")
		)
		(fp_line
			(start 0.12065 -0.2794)
			(end -0.12065 -0.2794)
			(stroke
				(width 0.1)
				(type default)
			)
			(layer "B.Fab")
		)
		(fp_line
			(start 0.12065 -0.305054)
			(end 0.12065 -0.2794)
			(stroke
				(width 0.1)
				(type default)
			)
			(layer "B.Fab")
		)
		(fp_line
			(start -0.120396 0.3048)
			(end -0.120396 0.2794)
			(stroke
				(width 0.1)
				(type default)
			)
			(layer "B.Fab")
		)
		(fp_line
			(start -0.120396 0.2794)
			(end 0.12065 0.2794)
			(stroke
				(width 0.1)
				(type default)
			)
			(layer "B.Fab")
		)
		(fp_line
			(start -0.12065 -0.2794)
			(end -0.12065 -0.3048)
			(stroke
				(width 0.1)
				(type default)
			)
			(layer "B.Fab")
		)
		(fp_line
			(start -0.12065 -0.3048)
			(end -0.67945 -0.3048)
			(stroke
				(width 0.1)
				(type default)
			)
			(layer "B.Fab")
		)
		(fp_line
			(start -0.67945 0.3048)
			(end -0.120396 0.3048)
			(stroke
				(width 0.1)
				(type default)
			)
			(layer "B.Fab")
		)
		(fp_line
			(start -0.67945 -0.3048)
			(end -0.67945 0.3048)
			(stroke
				(width 0.1)
				(type default)
			)
			(layer "B.Fab")
		)
		(pad "1" smd circle
			(at 0.40005 0)
			(size 0 0)
			(layers "B.Cu" "B.Mask" "B.Paste")
			(net "NIC2_AUX_PWR_EN")
		)
		(pad "2" smd circle
			(at -0.40005 0)
			(size 0 0)
			(layers "B.Cu" "B.Mask" "B.Paste")
			(net "GND")
		)
	)
	(footprint ""
		(layer "B.Cu")
		(at 231.901746 -146.912076)
		(property "Reference" "C2790"
			(at 0 0 0)
			(layer "B.SilkS")
			(hide yes)
			(effects
				(font
					(size 1.27 1.27)
				)
				(justify mirror)
			)
		)
		(property "Value" ""
			(at 0 0 0)
			(layer "B.Fab")
			(effects
				(font
					(size 1.27 1.27)
				)
				(justify mirror)
			)
		)
		(duplicate_pad_numbers_are_jumpers no)
		(fp_line
			(start -0.7874 -0.4064)
			(end -0.7874 0.4064)
			(stroke
				(width 0.1524)
				(type default)
			)
			(layer "B.SilkS")
		)
		(fp_line
			(start -0.7874 0.4064)
			(end 0.7874 0.4064)
			(stroke
				(width 0.1524)
				(type default)
			)
			(layer "B.SilkS")
		)
		(fp_line
			(start 0.7874 -0.4064)
			(end -0.7874 -0.4064)
			(stroke
				(width 0.1524)
				(type default)
			)
			(layer "B.SilkS")
		)
		(fp_line
			(start 0.7874 0.4064)
			(end 0.7874 -0.4064)
			(stroke
				(width 0.1524)
				(type default)
			)
			(layer "B.SilkS")
		)
		(fp_line
			(start -0.67945 -0.3048)
			(end -0.67945 0.3048)
			(stroke
				(width 0.1)
				(type default)
			)
			(layer "B.Fab")
		)
		(fp_line
			(start -0.67945 0.3048)
			(end -0.120396 0.3048)
			(stroke
				(width 0.1)
				(type default)
			)
			(layer "B.Fab")
		)
		(fp_line
			(start -0.12065 -0.3048)
			(end -0.67945 -0.3048)
			(stroke
				(width 0.1)
				(type default)
			)
			(layer "B.Fab")
		)
		(fp_line
			(start -0.12065 -0.2794)
			(end -0.12065 -0.3048)
			(stroke
				(width 0.1)
				(type default)
			)
			(layer "B.Fab")
		)
		(fp_line
			(start -0.120396 0.2794)
			(end 0.12065 0.2794)
			(stroke
				(width 0.1)
				(type default)
			)
			(layer "B.Fab")
		)
		(fp_line
			(start -0.120396 0.3048)
			(end -0.120396 0.2794)
			(stroke
				(width 0.1)
				(type default)
			)
			(layer "B.Fab")
		)
		(fp_line
			(start 0.12065 -0.305054)
			(end 0.12065 -0.2794)
			(stroke
				(width 0.1)
				(type default)
			)
			(layer "B.Fab")
		)
		(fp_line
			(start 0.12065 -0.2794)
			(end -0.12065 -0.2794)
			(stroke
				(width 0.1)
				(type default)
			)
			(layer "B.Fab")
		)
		(fp_line
			(start 0.12065 0.2794)
			(end 0.12065 0.3048)
			(stroke
				(width 0.1)
				(type default)
			)
			(layer "B.Fab")
		)
		(fp_line
			(start 0.12065 0.3048)
			(end 0.67945 0.3048)
			(stroke
				(width 0.1)
				(type default)
			)
			(layer "B.Fab")
		)
		(fp_line
			(start 0.67945 -0.305054)
			(end 0.12065 -0.305054)
			(stroke
				(width 0.1)
				(type default)
			)
			(layer "B.Fab")
		)
		(fp_line
			(start 0.67945 0.3048)
			(end 0.67945 -0.305054)
			(stroke
				(width 0.1)
				(type default)
			)
			(layer "B.Fab")
		)
		(pad "1" smd circle
			(at 0.40005 0 180)
			(size 0 0)
			(layers "B.Cu" "B.Mask" "B.Paste")
			(net "P3V3_CLK_GEN_VDDA100M_CK440_PEX")
		)
		(pad "2" smd circle
			(at -0.40005 0 180)
			(size 0 0)
			(layers "B.Cu" "B.Mask" "B.Paste")
			(net "GND")
		)
	)
)
